FILE_TYPE = MULTI_PHYS_TABLE;

PART 'CONN_JACK_1P_GH4_S_TH'
CLASS = IO 

{========================================================================================}
: CLS_PN         | VALUE           = JEDEC_TYPE                | ALT_SYMBOLS                 | DESCRIPTION                                            | CPN_STATUS ;
{========================================================================================}
 'G200-12733-01' |'73174-0470'     = 'P_M_JACK_1P_GH4_S_P325'  |'(P_M_JACK_1P_GH4_S_P325)'   |'CON,MCX,JACK,12.67MM HIGH'                             | ''
 'G200-12747-01' |'734140170'      = 'P_M_JACK_1P_GH4_S_P050'  |'(P_M_JACK_1P_GH4_S_P050)'   |'CON,MMCX,JACK,50OHM,GOLD PLATING,1.27MM_PITCH,TH'      | ''
 'G200-13091-01' |'2081680-1'      = 'P_F_JACK_1P_GH4_RA_P200' |'(P_F_JACK_1P_GH4_RA_P200)'  |'CON,SMA JACK,50 OHM,RA,SMT'                            | ''

END_PART

END.

